FILE_TYPE = MACRO_DRAWING;
SET COLOR_WIRE YELLOW;
SET COLOR_PROP MONO;
SET COLOR_DOT WHITE;
SET COLOR_ARC YELLOW;
SET COLOR_BODY GREEN;
SET COLOR_NOTE MONO;
SET PROP_DISPLAY VALUE;
SET PAGE_NUMBER P143;
FORCEADD OFFPAGE..5
(-14375 -1300);
FORCEPROP 2 LAST $XR0 149 
J 0
(-14660 -1300);
DISPLAY 0.638298 (-14660 -1300);
PAINT MONO (-14660 -1300);
FORCEPROP 2 LAST PATH I10
J 0
(-14650 -1250);
DISPLAY 1.021277 (-14650 -1250);
PAINT ORANGE (-14650 -1250);
DISPLAY INVISIBLE (-14650 -1250);
FORCEPROP 2 LAST CDS_LIB mstr_standard
J 0
(-14375 -1300);
PAINT MONO (-14375 -1300);
DISPLAY INVISIBLE (-14375 -1300);
FORCEPROP 1 LAST OFFPAGE TRUE
J 0
(-14050 -1425);
DISPLAY 0.872340 (-14050 -1425);
PAINT GREEN (-14050 -1425);
DISPLAY INVISIBLE (-14050 -1425);
FORCEPROP 1 LAST COMMENT_BODY TRUE
J 0
(-14275 -1375);
DISPLAY 0.872340 (-14275 -1375);
PAINT GREEN (-14275 -1375);
DISPLAY INVISIBLE (-14275 -1375);
FORCEADD OFFPAGE..5
(-14375 -1250);
FORCEPROP 2 LAST $XR0 149 
J 0
(-14660 -1250);
DISPLAY 0.638298 (-14660 -1250);
PAINT MONO (-14660 -1250);
FORCEPROP 2 LAST PATH I11
J 0
(-14650 -1200);
DISPLAY 1.021277 (-14650 -1200);
PAINT ORANGE (-14650 -1200);
DISPLAY INVISIBLE (-14650 -1200);
FORCEPROP 2 LAST CDS_LIB mstr_standard
J 0
(-14375 -1250);
PAINT MONO (-14375 -1250);
DISPLAY INVISIBLE (-14375 -1250);
FORCEPROP 1 LAST OFFPAGE TRUE
J 0
(-14050 -1375);
DISPLAY 0.872340 (-14050 -1375);
PAINT GREEN (-14050 -1375);
DISPLAY INVISIBLE (-14050 -1375);
FORCEPROP 1 LAST COMMENT_BODY TRUE
J 0
(-14275 -1325);
DISPLAY 0.872340 (-14275 -1325);
PAINT GREEN (-14275 -1325);
DISPLAY INVISIBLE (-14275 -1325);
FORCEADD OFFPAGE..5
(-14375 -1200);
FORCEPROP 2 LAST $XR0 149 
J 0
(-14660 -1200);
DISPLAY 0.638298 (-14660 -1200);
PAINT MONO (-14660 -1200);
FORCEPROP 2 LAST PATH I12
J 0
(-14650 -1150);
DISPLAY 1.021277 (-14650 -1150);
PAINT ORANGE (-14650 -1150);
DISPLAY INVISIBLE (-14650 -1150);
FORCEPROP 2 LAST CDS_LIB mstr_standard
J 0
(-14375 -1200);
PAINT MONO (-14375 -1200);
DISPLAY INVISIBLE (-14375 -1200);
FORCEPROP 1 LAST OFFPAGE TRUE
J 0
(-14050 -1325);
DISPLAY 0.872340 (-14050 -1325);
PAINT GREEN (-14050 -1325);
DISPLAY INVISIBLE (-14050 -1325);
FORCEPROP 1 LAST COMMENT_BODY TRUE
J 0
(-14275 -1275);
DISPLAY 0.872340 (-14275 -1275);
PAINT GREEN (-14275 -1275);
DISPLAY INVISIBLE (-14275 -1275);
FORCEADD OFFPAGE..5
(-14375 -1150);
FORCEPROP 2 LAST $XR0 149 
J 0
(-14660 -1150);
DISPLAY 0.638298 (-14660 -1150);
PAINT MONO (-14660 -1150);
FORCEPROP 2 LAST PATH I13
J 0
(-14650 -1100);
DISPLAY 1.021277 (-14650 -1100);
PAINT ORANGE (-14650 -1100);
DISPLAY INVISIBLE (-14650 -1100);
FORCEPROP 2 LAST CDS_LIB mstr_standard
J 0
(-14375 -1150);
PAINT MONO (-14375 -1150);
DISPLAY INVISIBLE (-14375 -1150);
FORCEPROP 1 LAST OFFPAGE TRUE
J 0
(-14050 -1275);
DISPLAY 0.872340 (-14050 -1275);
PAINT GREEN (-14050 -1275);
DISPLAY INVISIBLE (-14050 -1275);
FORCEPROP 1 LAST COMMENT_BODY TRUE
J 0
(-14275 -1225);
DISPLAY 0.872340 (-14275 -1225);
PAINT GREEN (-14275 -1225);
DISPLAY INVISIBLE (-14275 -1225);
FORCEADD OFFPAGE..5
(-14375 -1100);
FORCEPROP 2 LAST $XR0 149 
J 0
(-14660 -1100);
DISPLAY 0.638298 (-14660 -1100);
PAINT MONO (-14660 -1100);
FORCEPROP 2 LAST PATH I14
J 0
(-14650 -1050);
DISPLAY 1.021277 (-14650 -1050);
PAINT ORANGE (-14650 -1050);
DISPLAY INVISIBLE (-14650 -1050);
FORCEPROP 2 LAST CDS_LIB mstr_standard
J 0
(-14375 -1100);
PAINT MONO (-14375 -1100);
DISPLAY INVISIBLE (-14375 -1100);
FORCEPROP 1 LAST OFFPAGE TRUE
J 0
(-14050 -1225);
DISPLAY 0.872340 (-14050 -1225);
PAINT GREEN (-14050 -1225);
DISPLAY INVISIBLE (-14050 -1225);
FORCEPROP 1 LAST COMMENT_BODY TRUE
J 0
(-14275 -1175);
DISPLAY 0.872340 (-14275 -1175);
PAINT GREEN (-14275 -1175);
DISPLAY INVISIBLE (-14275 -1175);
FORCEADD OFFPAGE..5
(-14375 -1050);
FORCEPROP 2 LAST $XR0 149 
J 0
(-14660 -1050);
DISPLAY 0.638298 (-14660 -1050);
PAINT MONO (-14660 -1050);
FORCEPROP 2 LAST CDS_LIB mstr_standard
J 0
(-14375 -1050);
PAINT MONO (-14375 -1050);
DISPLAY INVISIBLE (-14375 -1050);
FORCEPROP 2 LAST PATH I15
J 0
(-14650 -1000);
DISPLAY 1.021277 (-14650 -1000);
PAINT ORANGE (-14650 -1000);
DISPLAY INVISIBLE (-14650 -1000);
FORCEPROP 1 LAST OFFPAGE TRUE
J 0
(-14050 -1175);
DISPLAY 0.872340 (-14050 -1175);
PAINT GREEN (-14050 -1175);
DISPLAY INVISIBLE (-14050 -1175);
FORCEPROP 1 LAST COMMENT_BODY TRUE
J 0
(-14275 -1125);
DISPLAY 0.872340 (-14275 -1125);
PAINT GREEN (-14275 -1125);
DISPLAY INVISIBLE (-14275 -1125);
FORCEADD OFFPAGE..5
(-14375 -1000);
FORCEPROP 2 LAST $XR0 149 
J 0
(-14660 -1000);
DISPLAY 0.638298 (-14660 -1000);
PAINT MONO (-14660 -1000);
FORCEPROP 2 LAST CDS_LIB mstr_standard
J 0
(-14375 -1000);
PAINT MONO (-14375 -1000);
DISPLAY INVISIBLE (-14375 -1000);
FORCEPROP 2 LAST PATH I16
J 0
(-14650 -950);
DISPLAY 1.021277 (-14650 -950);
PAINT ORANGE (-14650 -950);
DISPLAY INVISIBLE (-14650 -950);
FORCEPROP 1 LAST OFFPAGE TRUE
J 0
(-14050 -1125);
DISPLAY 0.872340 (-14050 -1125);
PAINT GREEN (-14050 -1125);
DISPLAY INVISIBLE (-14050 -1125);
FORCEPROP 1 LAST COMMENT_BODY TRUE
J 0
(-14275 -1075);
DISPLAY 0.872340 (-14275 -1075);
PAINT GREEN (-14275 -1075);
DISPLAY INVISIBLE (-14275 -1075);
FORCEADD OFFPAGE..5
(-14375 -950);
FORCEPROP 2 LAST $XR0 149 
J 0
(-14660 -950);
DISPLAY 0.638298 (-14660 -950);
PAINT MONO (-14660 -950);
FORCEPROP 2 LAST PATH I17
J 0
(-14650 -900);
DISPLAY 1.021277 (-14650 -900);
PAINT ORANGE (-14650 -900);
DISPLAY INVISIBLE (-14650 -900);
FORCEPROP 2 LAST CDS_LIB mstr_standard
J 0
(-14375 -950);
PAINT MONO (-14375 -950);
DISPLAY INVISIBLE (-14375 -950);
FORCEPROP 1 LAST OFFPAGE TRUE
J 0
(-14050 -1075);
DISPLAY 0.872340 (-14050 -1075);
PAINT GREEN (-14050 -1075);
DISPLAY INVISIBLE (-14050 -1075);
FORCEPROP 1 LAST COMMENT_BODY TRUE
J 0
(-14275 -1025);
DISPLAY 0.872340 (-14275 -1025);
PAINT GREEN (-14275 -1025);
DISPLAY INVISIBLE (-14275 -1025);
FORCEADD OFFPAGE..5
(-14375 -1800);
FORCEPROP 2 LAST $XR0 149 
J 0
(-14660 -1800);
DISPLAY 0.638298 (-14660 -1800);
PAINT MONO (-14660 -1800);
FORCEPROP 2 LAST CDS_LIB mstr_standard
J 0
(-14375 -1800);
PAINT MONO (-14375 -1800);
DISPLAY INVISIBLE (-14375 -1800);
FORCEPROP 2 LAST PATH I18
J 0
(-14650 -1750);
DISPLAY 1.021277 (-14650 -1750);
PAINT ORANGE (-14650 -1750);
DISPLAY INVISIBLE (-14650 -1750);
FORCEPROP 1 LAST OFFPAGE TRUE
J 0
(-14050 -1925);
DISPLAY 0.872340 (-14050 -1925);
PAINT GREEN (-14050 -1925);
DISPLAY INVISIBLE (-14050 -1925);
FORCEPROP 1 LAST COMMENT_BODY TRUE
J 0
(-14275 -1875);
DISPLAY 0.872340 (-14275 -1875);
PAINT GREEN (-14275 -1875);
DISPLAY INVISIBLE (-14275 -1875);
FORCEADD OFFPAGE..5
(-14375 -1950);
FORCEPROP 2 LAST $XR0 149 
J 0
(-14660 -1950);
DISPLAY 0.638298 (-14660 -1950);
PAINT MONO (-14660 -1950);
FORCEPROP 2 LAST CDS_LIB mstr_standard
J 0
(-14375 -1950);
PAINT MONO (-14375 -1950);
DISPLAY INVISIBLE (-14375 -1950);
FORCEPROP 2 LAST PATH I19
J 0
(-14650 -1900);
DISPLAY 1.021277 (-14650 -1900);
PAINT ORANGE (-14650 -1900);
DISPLAY INVISIBLE (-14650 -1900);
FORCEPROP 1 LAST OFFPAGE TRUE
J 0
(-14050 -2075);
DISPLAY 0.872340 (-14050 -2075);
PAINT GREEN (-14050 -2075);
DISPLAY INVISIBLE (-14050 -2075);
FORCEPROP 1 LAST COMMENT_BODY TRUE
J 0
(-14275 -2025);
DISPLAY 0.872340 (-14275 -2025);
PAINT GREEN (-14275 -2025);
DISPLAY INVISIBLE (-14275 -2025);
FORCEADD OFFPAGE..5
(-14375 -1650);
FORCEPROP 2 LAST $XR0 149 
J 0
(-14660 -1650);
DISPLAY 0.638298 (-14660 -1650);
PAINT MONO (-14660 -1650);
FORCEPROP 2 LAST CDS_LIB mstr_standard
J 0
(-14375 -1650);
PAINT MONO (-14375 -1650);
DISPLAY INVISIBLE (-14375 -1650);
FORCEPROP 2 LAST PATH I2
J 0
(-14650 -1600);
DISPLAY 1.021277 (-14650 -1600);
PAINT ORANGE (-14650 -1600);
DISPLAY INVISIBLE (-14650 -1600);
FORCEPROP 1 LAST OFFPAGE TRUE
J 0
(-14050 -1775);
DISPLAY 0.872340 (-14050 -1775);
PAINT GREEN (-14050 -1775);
DISPLAY INVISIBLE (-14050 -1775);
FORCEPROP 1 LAST COMMENT_BODY TRUE
J 0
(-14275 -1725);
DISPLAY 0.872340 (-14275 -1725);
PAINT GREEN (-14275 -1725);
DISPLAY INVISIBLE (-14275 -1725);
FORCEADD OFFPAGE..5
(-14375 -1850);
FORCEPROP 2 LAST $XR0 149 
J 0
(-14660 -1850);
DISPLAY 0.638298 (-14660 -1850);
PAINT MONO (-14660 -1850);
FORCEPROP 2 LAST CDS_LIB mstr_standard
J 0
(-14375 -1850);
PAINT MONO (-14375 -1850);
DISPLAY INVISIBLE (-14375 -1850);
FORCEPROP 2 LAST PATH I20
J 0
(-14650 -1800);
DISPLAY 1.021277 (-14650 -1800);
PAINT ORANGE (-14650 -1800);
DISPLAY INVISIBLE (-14650 -1800);
FORCEPROP 1 LAST OFFPAGE TRUE
J 0
(-14050 -1975);
DISPLAY 0.872340 (-14050 -1975);
PAINT GREEN (-14050 -1975);
DISPLAY INVISIBLE (-14050 -1975);
FORCEPROP 1 LAST COMMENT_BODY TRUE
J 0
(-14275 -1925);
DISPLAY 0.872340 (-14275 -1925);
PAINT GREEN (-14275 -1925);
DISPLAY INVISIBLE (-14275 -1925);
FORCEADD OFFPAGE..5
(-14375 -2000);
FORCEPROP 2 LAST $XR0 149 
J 0
(-14660 -2000);
DISPLAY 0.638298 (-14660 -2000);
PAINT MONO (-14660 -2000);
FORCEPROP 2 LAST CDS_LIB mstr_standard
J 0
(-14375 -2000);
PAINT MONO (-14375 -2000);
DISPLAY INVISIBLE (-14375 -2000);
FORCEPROP 2 LAST PATH I21
J 0
(-14650 -1950);
DISPLAY 1.021277 (-14650 -1950);
PAINT ORANGE (-14650 -1950);
DISPLAY INVISIBLE (-14650 -1950);
FORCEPROP 1 LAST OFFPAGE TRUE
J 0
(-14050 -2125);
DISPLAY 0.872340 (-14050 -2125);
PAINT GREEN (-14050 -2125);
DISPLAY INVISIBLE (-14050 -2125);
FORCEPROP 1 LAST COMMENT_BODY TRUE
J 0
(-14275 -2075);
DISPLAY 0.872340 (-14275 -2075);
PAINT GREEN (-14275 -2075);
DISPLAY INVISIBLE (-14275 -2075);
FORCEADD OFFPAGE..2
(-11050 -1150);
FORCEPROP 2 LAST $XR0 149 
J 0
(-10861 -1150);
DISPLAY 0.638298 (-10861 -1150);
PAINT MONO (-10861 -1150);
FORCEPROP 2 LAST PATH I23
J 0
(-10850 -1100);
DISPLAY 1.021277 (-10850 -1100);
PAINT ORANGE (-10850 -1100);
DISPLAY INVISIBLE (-10850 -1100);
FORCEPROP 2 LAST CDS_LIB mstr_standard
J 0
(-11050 -1150);
PAINT MONO (-11050 -1150);
DISPLAY INVISIBLE (-11050 -1150);
FORCEPROP 1 LAST OFFPAGE TRUE
J 0
(-10725 -1275);
DISPLAY 0.872340 (-10725 -1275);
PAINT GREEN (-10725 -1275);
DISPLAY INVISIBLE (-10725 -1275);
FORCEPROP 1 LAST COMMENT_BODY TRUE
J 0
(-11095 -1245);
DISPLAY 0.872340 (-11095 -1245);
PAINT GREEN (-11095 -1245);
DISPLAY INVISIBLE (-11095 -1245);
FORCEADD OFFPAGE..2
(-11050 -1200);
FORCEPROP 2 LAST $XR0 149 
J 0
(-10861 -1200);
DISPLAY 0.638298 (-10861 -1200);
PAINT MONO (-10861 -1200);
FORCEPROP 2 LAST PATH I24
J 0
(-10850 -1150);
DISPLAY 1.021277 (-10850 -1150);
PAINT ORANGE (-10850 -1150);
DISPLAY INVISIBLE (-10850 -1150);
FORCEPROP 2 LAST CDS_LIB mstr_standard
J 0
(-11050 -1200);
PAINT MONO (-11050 -1200);
DISPLAY INVISIBLE (-11050 -1200);
FORCEPROP 1 LAST OFFPAGE TRUE
J 0
(-10725 -1325);
DISPLAY 0.872340 (-10725 -1325);
PAINT GREEN (-10725 -1325);
DISPLAY INVISIBLE (-10725 -1325);
FORCEPROP 1 LAST COMMENT_BODY TRUE
J 0
(-11095 -1295);
DISPLAY 0.872340 (-11095 -1295);
PAINT GREEN (-11095 -1295);
DISPLAY INVISIBLE (-11095 -1295);
FORCEADD OFFPAGE..2
(-11050 -1250);
FORCEPROP 2 LAST $XR0 149 
J 0
(-10861 -1250);
DISPLAY 0.638298 (-10861 -1250);
PAINT MONO (-10861 -1250);
FORCEPROP 2 LAST PATH I25
J 0
(-10850 -1200);
DISPLAY 1.021277 (-10850 -1200);
PAINT ORANGE (-10850 -1200);
DISPLAY INVISIBLE (-10850 -1200);
FORCEPROP 2 LAST CDS_LIB mstr_standard
J 0
(-11050 -1250);
PAINT MONO (-11050 -1250);
DISPLAY INVISIBLE (-11050 -1250);
FORCEPROP 1 LAST OFFPAGE TRUE
J 0
(-10725 -1375);
DISPLAY 0.872340 (-10725 -1375);
PAINT GREEN (-10725 -1375);
DISPLAY INVISIBLE (-10725 -1375);
FORCEPROP 1 LAST COMMENT_BODY TRUE
J 0
(-11095 -1345);
DISPLAY 0.872340 (-11095 -1345);
PAINT GREEN (-11095 -1345);
DISPLAY INVISIBLE (-11095 -1345);
FORCEADD OFFPAGE..2
(-11050 -1300);
FORCEPROP 2 LAST $XR0 149 
J 0
(-10861 -1300);
DISPLAY 0.638298 (-10861 -1300);
PAINT MONO (-10861 -1300);
FORCEPROP 2 LAST PATH I26
J 0
(-10850 -1250);
DISPLAY 1.021277 (-10850 -1250);
PAINT ORANGE (-10850 -1250);
DISPLAY INVISIBLE (-10850 -1250);
FORCEPROP 2 LAST CDS_LIB mstr_standard
J 0
(-11050 -1300);
PAINT MONO (-11050 -1300);
DISPLAY INVISIBLE (-11050 -1300);
FORCEPROP 1 LAST OFFPAGE TRUE
J 0
(-10725 -1425);
DISPLAY 0.872340 (-10725 -1425);
PAINT GREEN (-10725 -1425);
DISPLAY INVISIBLE (-10725 -1425);
FORCEPROP 1 LAST COMMENT_BODY TRUE
J 0
(-11095 -1395);
DISPLAY 0.872340 (-11095 -1395);
PAINT GREEN (-11095 -1395);
DISPLAY INVISIBLE (-11095 -1395);
FORCEADD OFFPAGE..2
(-11050 -1350);
FORCEPROP 2 LAST $XR0 149 
J 0
(-10861 -1350);
DISPLAY 0.638298 (-10861 -1350);
PAINT MONO (-10861 -1350);
FORCEPROP 2 LAST PATH I27
J 0
(-10850 -1300);
DISPLAY 1.021277 (-10850 -1300);
PAINT ORANGE (-10850 -1300);
DISPLAY INVISIBLE (-10850 -1300);
FORCEPROP 2 LAST CDS_LIB mstr_standard
J 0
(-11050 -1350);
PAINT MONO (-11050 -1350);
DISPLAY INVISIBLE (-11050 -1350);
FORCEPROP 1 LAST OFFPAGE TRUE
J 0
(-10725 -1475);
DISPLAY 0.872340 (-10725 -1475);
PAINT GREEN (-10725 -1475);
DISPLAY INVISIBLE (-10725 -1475);
FORCEPROP 1 LAST COMMENT_BODY TRUE
J 0
(-11095 -1445);
DISPLAY 0.872340 (-11095 -1445);
PAINT GREEN (-11095 -1445);
DISPLAY INVISIBLE (-11095 -1445);
FORCEADD OFFPAGE..2
(-11050 -1400);
FORCEPROP 2 LAST $XR0 149 
J 0
(-10861 -1400);
DISPLAY 0.638298 (-10861 -1400);
PAINT MONO (-10861 -1400);
FORCEPROP 2 LAST PATH I28
J 0
(-10850 -1350);
DISPLAY 1.021277 (-10850 -1350);
PAINT ORANGE (-10850 -1350);
DISPLAY INVISIBLE (-10850 -1350);
FORCEPROP 2 LAST CDS_LIB mstr_standard
J 0
(-11050 -1400);
PAINT MONO (-11050 -1400);
DISPLAY INVISIBLE (-11050 -1400);
FORCEPROP 1 LAST OFFPAGE TRUE
J 0
(-10725 -1525);
DISPLAY 0.872340 (-10725 -1525);
PAINT GREEN (-10725 -1525);
DISPLAY INVISIBLE (-10725 -1525);
FORCEPROP 1 LAST COMMENT_BODY TRUE
J 0
(-11095 -1495);
DISPLAY 0.872340 (-11095 -1495);
PAINT GREEN (-11095 -1495);
DISPLAY INVISIBLE (-11095 -1495);
FORCEADD OFFPAGE..2
(-11050 -1450);
FORCEPROP 2 LAST $XR0 149 
J 0
(-10861 -1450);
DISPLAY 0.638298 (-10861 -1450);
PAINT MONO (-10861 -1450);
FORCEPROP 2 LAST PATH I29
J 0
(-10850 -1400);
DISPLAY 1.021277 (-10850 -1400);
PAINT ORANGE (-10850 -1400);
DISPLAY INVISIBLE (-10850 -1400);
FORCEPROP 2 LAST CDS_LIB mstr_standard
J 0
(-11050 -1450);
PAINT MONO (-11050 -1450);
DISPLAY INVISIBLE (-11050 -1450);
FORCEPROP 1 LAST OFFPAGE TRUE
J 0
(-10725 -1575);
DISPLAY 0.872340 (-10725 -1575);
PAINT GREEN (-10725 -1575);
DISPLAY INVISIBLE (-10725 -1575);
FORCEPROP 1 LAST COMMENT_BODY TRUE
J 0
(-11095 -1545);
DISPLAY 0.872340 (-11095 -1545);
PAINT GREEN (-11095 -1545);
DISPLAY INVISIBLE (-11095 -1545);
FORCEADD OFFPAGE..5
(-14375 -1600);
FORCEPROP 2 LAST $XR0 149 
J 0
(-14660 -1600);
DISPLAY 0.638298 (-14660 -1600);
PAINT MONO (-14660 -1600);
FORCEPROP 2 LAST CDS_LIB mstr_standard
J 0
(-14375 -1600);
PAINT MONO (-14375 -1600);
DISPLAY INVISIBLE (-14375 -1600);
FORCEPROP 2 LAST PATH I3
J 0
(-14650 -1550);
DISPLAY 1.021277 (-14650 -1550);
PAINT ORANGE (-14650 -1550);
DISPLAY INVISIBLE (-14650 -1550);
FORCEPROP 1 LAST OFFPAGE TRUE
J 0
(-14050 -1725);
DISPLAY 0.872340 (-14050 -1725);
PAINT GREEN (-14050 -1725);
DISPLAY INVISIBLE (-14050 -1725);
FORCEPROP 1 LAST COMMENT_BODY TRUE
J 0
(-14275 -1675);
DISPLAY 0.872340 (-14275 -1675);
PAINT GREEN (-14275 -1675);
DISPLAY INVISIBLE (-14275 -1675);
FORCEADD OFFPAGE..2
(-11050 -1500);
FORCEPROP 2 LAST $XR0 149 
J 0
(-10861 -1500);
DISPLAY 0.638298 (-10861 -1500);
PAINT MONO (-10861 -1500);
FORCEPROP 2 LAST PATH I30
J 0
(-10850 -1450);
DISPLAY 1.021277 (-10850 -1450);
PAINT ORANGE (-10850 -1450);
DISPLAY INVISIBLE (-10850 -1450);
FORCEPROP 2 LAST CDS_LIB mstr_standard
J 0
(-11050 -1500);
PAINT MONO (-11050 -1500);
DISPLAY INVISIBLE (-11050 -1500);
FORCEPROP 1 LAST OFFPAGE TRUE
J 0
(-10725 -1625);
DISPLAY 0.872340 (-10725 -1625);
PAINT GREEN (-10725 -1625);
DISPLAY INVISIBLE (-10725 -1625);
FORCEPROP 1 LAST COMMENT_BODY TRUE
J 0
(-11095 -1595);
DISPLAY 0.872340 (-11095 -1595);
PAINT GREEN (-11095 -1595);
DISPLAY INVISIBLE (-11095 -1595);
FORCEADD OFFPAGE..2
(-11050 -1550);
FORCEPROP 2 LAST $XR0 149 
J 0
(-10861 -1550);
DISPLAY 0.638298 (-10861 -1550);
PAINT MONO (-10861 -1550);
FORCEPROP 2 LAST PATH I31
J 0
(-10850 -1500);
DISPLAY 1.021277 (-10850 -1500);
PAINT ORANGE (-10850 -1500);
DISPLAY INVISIBLE (-10850 -1500);
FORCEPROP 2 LAST CDS_LIB mstr_standard
J 0
(-11050 -1550);
PAINT MONO (-11050 -1550);
DISPLAY INVISIBLE (-11050 -1550);
FORCEPROP 1 LAST OFFPAGE TRUE
J 0
(-10725 -1675);
DISPLAY 0.872340 (-10725 -1675);
PAINT GREEN (-10725 -1675);
DISPLAY INVISIBLE (-10725 -1675);
FORCEPROP 1 LAST COMMENT_BODY TRUE
J 0
(-11095 -1645);
DISPLAY 0.872340 (-11095 -1645);
PAINT GREEN (-11095 -1645);
DISPLAY INVISIBLE (-11095 -1645);
FORCEADD OFFPAGE..2
(-11050 -1650);
FORCEPROP 2 LAST $XR0 149 
J 0
(-10861 -1650);
DISPLAY 0.638298 (-10861 -1650);
PAINT MONO (-10861 -1650);
FORCEPROP 2 LAST CDS_LIB mstr_standard
J 0
(-11050 -1650);
PAINT MONO (-11050 -1650);
DISPLAY INVISIBLE (-11050 -1650);
FORCEPROP 2 LAST PATH I33
J 0
(-10850 -1600);
DISPLAY 1.021277 (-10850 -1600);
PAINT ORANGE (-10850 -1600);
DISPLAY INVISIBLE (-10850 -1600);
FORCEPROP 1 LAST OFFPAGE TRUE
J 0
(-10725 -1775);
DISPLAY 0.872340 (-10725 -1775);
PAINT GREEN (-10725 -1775);
DISPLAY INVISIBLE (-10725 -1775);
FORCEPROP 1 LAST COMMENT_BODY TRUE
J 0
(-11095 -1745);
DISPLAY 0.872340 (-11095 -1745);
PAINT GREEN (-11095 -1745);
DISPLAY INVISIBLE (-11095 -1745);
FORCEADD OFFPAGE..2
(-11050 -1700);
FORCEPROP 2 LAST $XR0 149 
J 0
(-10861 -1700);
DISPLAY 0.638298 (-10861 -1700);
PAINT MONO (-10861 -1700);
FORCEPROP 2 LAST CDS_LIB mstr_standard
J 0
(-11050 -1700);
PAINT MONO (-11050 -1700);
DISPLAY INVISIBLE (-11050 -1700);
FORCEPROP 2 LAST PATH I34
J 0
(-10850 -1650);
DISPLAY 1.021277 (-10850 -1650);
PAINT ORANGE (-10850 -1650);
DISPLAY INVISIBLE (-10850 -1650);
FORCEPROP 1 LAST OFFPAGE TRUE
J 0
(-10725 -1825);
DISPLAY 0.872340 (-10725 -1825);
PAINT GREEN (-10725 -1825);
DISPLAY INVISIBLE (-10725 -1825);
FORCEPROP 1 LAST COMMENT_BODY TRUE
J 0
(-11095 -1795);
DISPLAY 0.872340 (-11095 -1795);
PAINT GREEN (-11095 -1795);
DISPLAY INVISIBLE (-11095 -1795);
FORCEADD OFFPAGE..2
(-11050 -1100);
FORCEPROP 2 LAST $XR0 149 
J 0
(-10861 -1100);
DISPLAY 0.638298 (-10861 -1100);
PAINT MONO (-10861 -1100);
FORCEPROP 2 LAST PATH I36
J 0
(-10850 -1050);
DISPLAY 1.021277 (-10850 -1050);
PAINT ORANGE (-10850 -1050);
DISPLAY INVISIBLE (-10850 -1050);
FORCEPROP 2 LAST CDS_LIB mstr_standard
J 0
(-11050 -1100);
PAINT MONO (-11050 -1100);
DISPLAY INVISIBLE (-11050 -1100);
FORCEPROP 1 LAST OFFPAGE TRUE
J 0
(-10725 -1225);
DISPLAY 0.872340 (-10725 -1225);
PAINT GREEN (-10725 -1225);
DISPLAY INVISIBLE (-10725 -1225);
FORCEPROP 1 LAST COMMENT_BODY TRUE
J 0
(-11095 -1195);
DISPLAY 0.872340 (-11095 -1195);
PAINT GREEN (-11095 -1195);
DISPLAY INVISIBLE (-11095 -1195);
FORCEADD OFFPAGE..2
(-11050 -1050);
FORCEPROP 2 LAST $XR0 149 
J 0
(-10861 -1050);
DISPLAY 0.638298 (-10861 -1050);
PAINT MONO (-10861 -1050);
FORCEPROP 2 LAST CDS_LIB mstr_standard
J 0
(-11050 -1050);
PAINT MONO (-11050 -1050);
DISPLAY INVISIBLE (-11050 -1050);
FORCEPROP 2 LAST PATH I37
J 0
(-10850 -1000);
DISPLAY 1.021277 (-10850 -1000);
PAINT ORANGE (-10850 -1000);
DISPLAY INVISIBLE (-10850 -1000);
FORCEPROP 1 LAST OFFPAGE TRUE
J 0
(-10725 -1175);
DISPLAY 0.872340 (-10725 -1175);
PAINT GREEN (-10725 -1175);
DISPLAY INVISIBLE (-10725 -1175);
FORCEPROP 1 LAST COMMENT_BODY TRUE
J 0
(-11095 -1145);
DISPLAY 0.872340 (-11095 -1145);
PAINT GREEN (-11095 -1145);
DISPLAY INVISIBLE (-11095 -1145);
FORCEADD OFFPAGE..2
(-11050 -1000);
FORCEPROP 2 LAST $XR0 149 
J 0
(-10861 -1000);
DISPLAY 0.638298 (-10861 -1000);
PAINT MONO (-10861 -1000);
FORCEPROP 2 LAST CDS_LIB mstr_standard
J 0
(-11050 -1000);
PAINT MONO (-11050 -1000);
DISPLAY INVISIBLE (-11050 -1000);
FORCEPROP 2 LAST PATH I38
J 0
(-10850 -950);
DISPLAY 1.021277 (-10850 -950);
PAINT ORANGE (-10850 -950);
DISPLAY INVISIBLE (-10850 -950);
FORCEPROP 1 LAST OFFPAGE TRUE
J 0
(-10725 -1125);
DISPLAY 0.872340 (-10725 -1125);
PAINT GREEN (-10725 -1125);
DISPLAY INVISIBLE (-10725 -1125);
FORCEPROP 1 LAST COMMENT_BODY TRUE
J 0
(-11095 -1095);
DISPLAY 0.872340 (-11095 -1095);
PAINT GREEN (-11095 -1095);
DISPLAY INVISIBLE (-11095 -1095);
FORCEADD OFFPAGE..2
(-11050 -1600);
FORCEPROP 2 LAST $XR0 149 
J 0
(-10861 -1600);
DISPLAY 0.638298 (-10861 -1600);
PAINT MONO (-10861 -1600);
FORCEPROP 2 LAST PATH I39
J 0
(-10850 -1550);
DISPLAY 1.021277 (-10850 -1550);
PAINT ORANGE (-10850 -1550);
DISPLAY INVISIBLE (-10850 -1550);
FORCEPROP 2 LAST CDS_LIB mstr_standard
J 0
(-11050 -1600);
PAINT MONO (-11050 -1600);
DISPLAY INVISIBLE (-11050 -1600);
FORCEPROP 1 LAST OFFPAGE TRUE
J 0
(-10725 -1725);
DISPLAY 0.872340 (-10725 -1725);
PAINT GREEN (-10725 -1725);
DISPLAY INVISIBLE (-10725 -1725);
FORCEPROP 1 LAST COMMENT_BODY TRUE
J 0
(-11095 -1695);
DISPLAY 0.872340 (-11095 -1695);
PAINT GREEN (-11095 -1695);
DISPLAY INVISIBLE (-11095 -1695);
FORCEADD OFFPAGE..5
(-14375 -1550);
FORCEPROP 2 LAST $XR0 149 
J 0
(-14660 -1550);
DISPLAY 0.638298 (-14660 -1550);
PAINT MONO (-14660 -1550);
FORCEPROP 2 LAST PATH I4
J 0
(-14650 -1500);
DISPLAY 1.021277 (-14650 -1500);
PAINT ORANGE (-14650 -1500);
DISPLAY INVISIBLE (-14650 -1500);
FORCEPROP 2 LAST CDS_LIB mstr_standard
J 0
(-14375 -1550);
PAINT MONO (-14375 -1550);
DISPLAY INVISIBLE (-14375 -1550);
FORCEPROP 1 LAST OFFPAGE TRUE
J 0
(-14050 -1675);
DISPLAY 0.872340 (-14050 -1675);
PAINT GREEN (-14050 -1675);
DISPLAY INVISIBLE (-14050 -1675);
FORCEPROP 1 LAST COMMENT_BODY TRUE
J 0
(-14275 -1625);
DISPLAY 0.872340 (-14275 -1625);
PAINT GREEN (-14275 -1625);
DISPLAY INVISIBLE (-14275 -1625);
FORCEADD OFFPAGE..2
(-11050 -1900);
FORCEPROP 2 LAST $XR0 149 
J 0
(-10861 -1900);
DISPLAY 0.638298 (-10861 -1900);
PAINT MONO (-10861 -1900);
FORCEPROP 2 LAST CDS_LIB mstr_standard
J 0
(-11050 -1900);
PAINT MONO (-11050 -1900);
DISPLAY INVISIBLE (-11050 -1900);
FORCEPROP 2 LAST PATH I40
J 0
(-10850 -1850);
DISPLAY 1.021277 (-10850 -1850);
PAINT ORANGE (-10850 -1850);
DISPLAY INVISIBLE (-10850 -1850);
FORCEPROP 1 LAST OFFPAGE TRUE
J 0
(-10725 -2025);
DISPLAY 0.872340 (-10725 -2025);
PAINT GREEN (-10725 -2025);
DISPLAY INVISIBLE (-10725 -2025);
FORCEPROP 1 LAST COMMENT_BODY TRUE
J 0
(-11095 -1995);
DISPLAY 0.872340 (-11095 -1995);
PAINT GREEN (-11095 -1995);
DISPLAY INVISIBLE (-11095 -1995);
FORCEADD OFFPAGE..2
(-11050 -1850);
FORCEPROP 2 LAST $XR0 149 
J 0
(-10861 -1850);
DISPLAY 0.638298 (-10861 -1850);
PAINT MONO (-10861 -1850);
FORCEPROP 2 LAST CDS_LIB mstr_standard
J 0
(-11050 -1850);
PAINT MONO (-11050 -1850);
DISPLAY INVISIBLE (-11050 -1850);
FORCEPROP 2 LAST PATH I41
J 0
(-10850 -1800);
DISPLAY 1.021277 (-10850 -1800);
PAINT ORANGE (-10850 -1800);
DISPLAY INVISIBLE (-10850 -1800);
FORCEPROP 1 LAST OFFPAGE TRUE
J 0
(-10725 -1975);
DISPLAY 0.872340 (-10725 -1975);
PAINT GREEN (-10725 -1975);
DISPLAY INVISIBLE (-10725 -1975);
FORCEPROP 1 LAST COMMENT_BODY TRUE
J 0
(-11095 -1945);
DISPLAY 0.872340 (-11095 -1945);
PAINT GREEN (-11095 -1945);
DISPLAY INVISIBLE (-11095 -1945);
FORCEADD OFFPAGE..2
(-11050 -1800);
FORCEPROP 2 LAST $XR0 149 
J 0
(-10861 -1800);
DISPLAY 0.638298 (-10861 -1800);
PAINT MONO (-10861 -1800);
FORCEPROP 2 LAST PATH I42
J 0
(-10850 -1750);
DISPLAY 1.021277 (-10850 -1750);
PAINT ORANGE (-10850 -1750);
DISPLAY INVISIBLE (-10850 -1750);
FORCEPROP 2 LAST CDS_LIB mstr_standard
J 0
(-11050 -1800);
PAINT MONO (-11050 -1800);
DISPLAY INVISIBLE (-11050 -1800);
FORCEPROP 1 LAST OFFPAGE TRUE
J 0
(-10725 -1925);
DISPLAY 0.872340 (-10725 -1925);
PAINT GREEN (-10725 -1925);
DISPLAY INVISIBLE (-10725 -1925);
FORCEPROP 1 LAST COMMENT_BODY TRUE
J 0
(-11095 -1895);
DISPLAY 0.872340 (-11095 -1895);
PAINT GREEN (-11095 -1895);
DISPLAY INVISIBLE (-11095 -1895);
FORCEADD OFFPAGE..2
(-11050 -2050);
FORCEPROP 2 LAST $XR0 149 
J 0
(-10861 -2050);
DISPLAY 0.638298 (-10861 -2050);
PAINT MONO (-10861 -2050);
FORCEPROP 2 LAST CDS_LIB mstr_standard
J 0
(-11050 -2050);
PAINT MONO (-11050 -2050);
DISPLAY INVISIBLE (-11050 -2050);
FORCEPROP 2 LAST PATH I43
J 0
(-10850 -2000);
DISPLAY 1.021277 (-10850 -2000);
PAINT ORANGE (-10850 -2000);
DISPLAY INVISIBLE (-10850 -2000);
FORCEPROP 1 LAST OFFPAGE TRUE
J 0
(-10725 -2175);
DISPLAY 0.872340 (-10725 -2175);
PAINT GREEN (-10725 -2175);
DISPLAY INVISIBLE (-10725 -2175);
FORCEPROP 1 LAST COMMENT_BODY TRUE
J 0
(-11095 -2145);
DISPLAY 0.872340 (-11095 -2145);
PAINT GREEN (-11095 -2145);
DISPLAY INVISIBLE (-11095 -2145);
FORCEADD OFFPAGE..2
(-11050 -2000);
FORCEPROP 2 LAST $XR0 149 
J 0
(-10861 -2000);
DISPLAY 0.638298 (-10861 -2000);
PAINT MONO (-10861 -2000);
FORCEPROP 2 LAST PATH I44
J 0
(-10850 -1950);
DISPLAY 1.021277 (-10850 -1950);
PAINT ORANGE (-10850 -1950);
DISPLAY INVISIBLE (-10850 -1950);
FORCEPROP 2 LAST CDS_LIB mstr_standard
J 0
(-11050 -2000);
PAINT MONO (-11050 -2000);
DISPLAY INVISIBLE (-11050 -2000);
FORCEPROP 1 LAST OFFPAGE TRUE
J 0
(-10725 -2125);
DISPLAY 0.872340 (-10725 -2125);
PAINT GREEN (-10725 -2125);
DISPLAY INVISIBLE (-10725 -2125);
FORCEPROP 1 LAST COMMENT_BODY TRUE
J 0
(-11095 -2095);
DISPLAY 0.872340 (-11095 -2095);
PAINT GREEN (-11095 -2095);
DISPLAY INVISIBLE (-11095 -2095);
FORCEADD OFFPAGE..2
(-11050 -2550);
FORCEPROP 2 LAST $XR0 149 
J 0
(-10856 -2550);
DISPLAY 0.638298 (-10856 -2550);
PAINT MONO (-10856 -2550);
FORCEPROP 2 LAST PATH I45
J 0
(-10525 -2500);
DISPLAY 1.021277 (-10525 -2500);
PAINT ORANGE (-10525 -2500);
DISPLAY INVISIBLE (-10525 -2500);
FORCEPROP 2 LAST CDS_LIB mstr_standard
J 0
(-11050 -2550);
PAINT MONO (-11050 -2550);
DISPLAY INVISIBLE (-11050 -2550);
FORCEPROP 1 LAST OFFPAGE TRUE
J 0
(-10725 -2675);
DISPLAY 0.872340 (-10725 -2675);
PAINT GREEN (-10725 -2675);
DISPLAY INVISIBLE (-10725 -2675);
FORCEPROP 1 LAST COMMENT_BODY TRUE
J 0
(-11095 -2645);
DISPLAY 0.872340 (-11095 -2645);
PAINT GREEN (-11095 -2645);
DISPLAY INVISIBLE (-11095 -2645);
FORCEADD OFFPAGE..2
(-11050 -2600);
FORCEPROP 2 LAST $XR0 149 
J 0
(-10861 -2600);
DISPLAY 0.638298 (-10861 -2600);
PAINT MONO (-10861 -2600);
FORCEPROP 2 LAST PATH I46
J 0
(-10850 -2550);
DISPLAY 1.021277 (-10850 -2550);
PAINT ORANGE (-10850 -2550);
DISPLAY INVISIBLE (-10850 -2550);
FORCEPROP 2 LAST CDS_LIB mstr_standard
J 0
(-11050 -2600);
PAINT MONO (-11050 -2600);
DISPLAY INVISIBLE (-11050 -2600);
FORCEPROP 1 LAST OFFPAGE TRUE
J 0
(-10725 -2725);
DISPLAY 0.872340 (-10725 -2725);
PAINT GREEN (-10725 -2725);
DISPLAY INVISIBLE (-10725 -2725);
FORCEPROP 1 LAST COMMENT_BODY TRUE
J 0
(-11095 -2695);
DISPLAY 0.872340 (-11095 -2695);
PAINT GREEN (-11095 -2695);
DISPLAY INVISIBLE (-11095 -2695);
FORCEADD OFFPAGE..2
(-11050 -2700);
FORCEPROP 2 LAST $XR0 149 
J 0
(-10861 -2700);
DISPLAY 0.638298 (-10861 -2700);
PAINT MONO (-10861 -2700);
FORCEPROP 2 LAST CDS_LIB mstr_standard
J 0
(-11050 -2700);
PAINT MONO (-11050 -2700);
DISPLAY INVISIBLE (-11050 -2700);
FORCEPROP 2 LAST PATH I47
J 0
(-10850 -2650);
DISPLAY 1.021277 (-10850 -2650);
PAINT ORANGE (-10850 -2650);
DISPLAY INVISIBLE (-10850 -2650);
FORCEPROP 1 LAST OFFPAGE TRUE
J 0
(-10725 -2825);
DISPLAY 0.872340 (-10725 -2825);
PAINT GREEN (-10725 -2825);
DISPLAY INVISIBLE (-10725 -2825);
FORCEPROP 1 LAST COMMENT_BODY TRUE
J 0
(-11095 -2795);
DISPLAY 0.872340 (-11095 -2795);
PAINT GREEN (-11095 -2795);
DISPLAY INVISIBLE (-11095 -2795);
FORCEADD OFFPAGE..2
(-11050 -2750);
FORCEPROP 2 LAST $XR0 149 
J 0
(-10861 -2750);
DISPLAY 0.638298 (-10861 -2750);
PAINT MONO (-10861 -2750);
FORCEPROP 2 LAST PATH I48
J 0
(-10850 -2700);
DISPLAY 1.021277 (-10850 -2700);
PAINT ORANGE (-10850 -2700);
DISPLAY INVISIBLE (-10850 -2700);
FORCEPROP 2 LAST CDS_LIB mstr_standard
J 0
(-11050 -2750);
PAINT MONO (-11050 -2750);
DISPLAY INVISIBLE (-11050 -2750);
FORCEPROP 1 LAST OFFPAGE TRUE
J 0
(-10725 -2875);
DISPLAY 0.872340 (-10725 -2875);
PAINT GREEN (-10725 -2875);
DISPLAY INVISIBLE (-10725 -2875);
FORCEPROP 1 LAST COMMENT_BODY TRUE
J 0
(-11095 -2845);
DISPLAY 0.872340 (-11095 -2845);
PAINT GREEN (-11095 -2845);
DISPLAY INVISIBLE (-11095 -2845);
FORCEADD OFFPAGE..2
(-11050 -2350);
FORCEPROP 2 LAST $XR0 149 
J 0
(-10861 -2350);
DISPLAY 0.638298 (-10861 -2350);
PAINT MONO (-10861 -2350);
FORCEPROP 2 LAST PATH I49
J 0
(-10850 -2300);
DISPLAY 1.021277 (-10850 -2300);
PAINT ORANGE (-10850 -2300);
DISPLAY INVISIBLE (-10850 -2300);
FORCEPROP 2 LAST CDS_LIB mstr_standard
J 0
(-11050 -2350);
PAINT MONO (-11050 -2350);
DISPLAY INVISIBLE (-11050 -2350);
FORCEPROP 1 LAST OFFPAGE TRUE
J 0
(-10725 -2475);
DISPLAY 0.872340 (-10725 -2475);
PAINT GREEN (-10725 -2475);
DISPLAY INVISIBLE (-10725 -2475);
FORCEPROP 1 LAST COMMENT_BODY TRUE
J 0
(-11095 -2445);
DISPLAY 0.872340 (-11095 -2445);
PAINT GREEN (-11095 -2445);
DISPLAY INVISIBLE (-11095 -2445);
FORCEADD OFFPAGE..5
(-14375 -1500);
FORCEPROP 2 LAST $XR0 149 
J 0
(-14660 -1500);
DISPLAY 0.638298 (-14660 -1500);
PAINT MONO (-14660 -1500);
FORCEPROP 2 LAST PATH I5
J 0
(-14650 -1450);
DISPLAY 1.021277 (-14650 -1450);
PAINT ORANGE (-14650 -1450);
DISPLAY INVISIBLE (-14650 -1450);
FORCEPROP 2 LAST CDS_LIB mstr_standard
J 0
(-14375 -1500);
PAINT MONO (-14375 -1500);
DISPLAY INVISIBLE (-14375 -1500);
FORCEPROP 1 LAST OFFPAGE TRUE
J 0
(-14050 -1625);
DISPLAY 0.872340 (-14050 -1625);
PAINT GREEN (-14050 -1625);
DISPLAY INVISIBLE (-14050 -1625);
FORCEPROP 1 LAST COMMENT_BODY TRUE
J 0
(-14275 -1575);
DISPLAY 0.872340 (-14275 -1575);
PAINT GREEN (-14275 -1575);
DISPLAY INVISIBLE (-14275 -1575);
FORCEADD OFFPAGE..2
(-11050 -2300);
FORCEPROP 2 LAST $XR0 149 
J 0
(-10861 -2300);
DISPLAY 0.638298 (-10861 -2300);
PAINT MONO (-10861 -2300);
FORCEPROP 2 LAST PATH I50
J 0
(-10850 -2250);
DISPLAY 1.021277 (-10850 -2250);
PAINT ORANGE (-10850 -2250);
DISPLAY INVISIBLE (-10850 -2250);
FORCEPROP 2 LAST CDS_LIB mstr_standard
J 0
(-11050 -2300);
PAINT MONO (-11050 -2300);
DISPLAY INVISIBLE (-11050 -2300);
FORCEPROP 1 LAST OFFPAGE TRUE
J 0
(-10725 -2425);
DISPLAY 0.872340 (-10725 -2425);
PAINT GREEN (-10725 -2425);
DISPLAY INVISIBLE (-10725 -2425);
FORCEPROP 1 LAST COMMENT_BODY TRUE
J 0
(-11095 -2395);
DISPLAY 0.872340 (-11095 -2395);
PAINT GREEN (-11095 -2395);
DISPLAY INVISIBLE (-11095 -2395);
FORCEADD OFFPAGE..2
(-11050 -2400);
FORCEPROP 2 LAST $XR0 149 
J 0
(-10861 -2400);
DISPLAY 0.638298 (-10861 -2400);
PAINT MONO (-10861 -2400);
FORCEPROP 2 LAST PATH I51
J 0
(-10850 -2350);
DISPLAY 1.021277 (-10850 -2350);
PAINT ORANGE (-10850 -2350);
DISPLAY INVISIBLE (-10850 -2350);
FORCEPROP 2 LAST CDS_LIB mstr_standard
J 0
(-11050 -2400);
PAINT MONO (-11050 -2400);
DISPLAY INVISIBLE (-11050 -2400);
FORCEPROP 1 LAST OFFPAGE TRUE
J 0
(-10725 -2525);
DISPLAY 0.872340 (-10725 -2525);
PAINT GREEN (-10725 -2525);
DISPLAY INVISIBLE (-10725 -2525);
FORCEPROP 1 LAST COMMENT_BODY TRUE
J 0
(-11095 -2495);
DISPLAY 0.872340 (-11095 -2495);
PAINT GREEN (-11095 -2495);
DISPLAY INVISIBLE (-11095 -2495);
FORCEADD OFFPAGE..2
(-11050 -2450);
FORCEPROP 2 LAST $XR0 149 
J 0
(-10861 -2450);
DISPLAY 0.638298 (-10861 -2450);
PAINT MONO (-10861 -2450);
FORCEPROP 2 LAST PATH I52
J 0
(-10850 -2400);
DISPLAY 1.021277 (-10850 -2400);
PAINT ORANGE (-10850 -2400);
DISPLAY INVISIBLE (-10850 -2400);
FORCEPROP 2 LAST CDS_LIB mstr_standard
J 0
(-11050 -2450);
PAINT MONO (-11050 -2450);
DISPLAY INVISIBLE (-11050 -2450);
FORCEPROP 1 LAST OFFPAGE TRUE
J 0
(-10725 -2575);
DISPLAY 0.872340 (-10725 -2575);
PAINT GREEN (-10725 -2575);
DISPLAY INVISIBLE (-10725 -2575);
FORCEPROP 1 LAST COMMENT_BODY TRUE
J 0
(-11095 -2545);
DISPLAY 0.872340 (-11095 -2545);
PAINT GREEN (-11095 -2545);
DISPLAY INVISIBLE (-11095 -2545);
FORCEADD GND..1
R 3
(-10250 -2200);
FORCEPROP 3 LASTPIN (-10300 -2200) SIG_NAME GND\g
J 0
(-10290 -2190);
DISPLAY 0.659574 (-10290 -2190);
PAINT MONO (-10290 -2190);
DISPLAY INVISIBLE (-10290 -2190);
FORCEPROP 1 LAST VOLTAGE 0.0V
R 1
J 2
(-10207 -2155);
DISPLAY 0.340426 (-10207 -2155);
PAINT GREEN (-10207 -2155);
DISPLAY INVISIBLE (-10207 -2155);
FORCEPROP 1 LAST SIZE 1B
R 1
J 2
(-10200 -2275);
DISPLAY 0.872340 (-10200 -2275);
PAINT AQUA (-10200 -2275);
DISPLAY INVISIBLE (-10200 -2275);
FORCEPROP 2 LAST CDS_LIB mstr_symbols
J 2
(-10250 -2200);
PAINT MONO (-10250 -2200);
DISPLAY INVISIBLE (-10250 -2200);
FORCEPROP 1 LAST PATH I54
R 1
J 2
(-10250 -2275);
DISPLAY 0.872340 (-10250 -2275);
PAINT AQUA (-10250 -2275);
DISPLAY INVISIBLE (-10250 -2275);
FORCEPROP 1 LAST BODY_TYPE PLUMBING
R 1
J 2
(-10207 -2155);
DISPLAY 0.340426 (-10207 -2155);
PAINT GREEN (-10207 -2155);
DISPLAY INVISIBLE (-10207 -2155);
FORCEPROP 1 LAST HDL_POWER GND
R 1
J 2
(-10400 -2200);
DISPLAY 0.872340 (-10400 -2200);
PAINT GREEN (-10400 -2200);
DISPLAY INVISIBLE (-10400 -2200);
FORCEADD CAP..1
R 3
(-10500 -2200);
FORCEPROP 1 LAST VALUE 0.1UF
J 2
(-10525 -2350);
DISPLAY 0.617021 (-10525 -2350);
PAINT SKYBLUE (-10525 -2350);
FORCEPROP 1 LAST LOCATION C25W22
J 2
(-10525 -2250);
DISPLAY 0.617021 (-10525 -2250);
PAINT AQUA (-10525 -2250);
FORCEPROP 1 LAST VOLTAGE 16V
J 2
(-10525 -2400);
DISPLAY 0.617021 (-10525 -2400);
PAINT SKYBLUE (-10525 -2400);
FORCEPROP 1 LAST MATERIAL X7R
J 2
(-10525 -2500);
DISPLAY 0.617021 (-10525 -2500);
PAINT SKYBLUE (-10525 -2500);
FORCEPROP 1 LAST TOLERANCE 10%
J 2
(-10525 -2450);
DISPLAY 0.617021 (-10525 -2450);
PAINT SKYBLUE (-10525 -2450);
FORCEPROP 1 LAST PACK_TYPE 0402LF
J 2
(-10525 -2300);
DISPLAY 0.617021 (-10525 -2300);
PAINT SKYBLUE (-10525 -2300);
FORCEPROP 1 LASTPIN (-10600 -2200) $PN 1
R 1
J 2
(-10580 -2210);
DISPLAY 0.787234 (-10580 -2210);
PAINT ORANGE (-10580 -2210);
DISPLAY INVISIBLE (-10580 -2210);
FORCEPROP 1 LASTPIN (-10400 -2200) $PN 2
R 1
J 2
(-10380 -2210);
DISPLAY 0.787234 (-10380 -2210);
PAINT ORANGE (-10380 -2210);
DISPLAY INVISIBLE (-10380 -2210);
FORCEPROP 1 LAST PATH I55
R 1
J 2
(-10650 -2250);
DISPLAY 0.978723 (-10650 -2250);
PAINT WHITE (-10650 -2250);
DISPLAY INVISIBLE (-10650 -2250);
FORCEPROP 1 LAST PART_NUMBER A36096-030
R 1
J 2
(-10350 -2250);
DISPLAY 0.617021 (-10350 -2250);
PAINT BLUE (-10350 -2250);
DISPLAY INVISIBLE (-10350 -2250);
FORCEPROP 0 LAST ROOM BMC
R 1
J 2
(-10700 -2250);
DISPLAY 1.021277 (-10700 -2250);
PAINT ORANGE (-10700 -2250);
DISPLAY INVISIBLE (-10700 -2250);
FORCEPROP 0 LAST BOM_COST SM_CONTROLLER
R 1
J 2
(-10700 -2250);
DISPLAY 1.021277 (-10700 -2250);
PAINT ORANGE (-10700 -2250);
DISPLAY INVISIBLE (-10700 -2250);
FORCEPROP 2 LAST CDS_LIB mstr_discrete
R 1
J 2
(-10500 -2200);
PAINT MONO (-10500 -2200);
DISPLAY INVISIBLE (-10500 -2200);
FORCEADD GND..1
R 1
(-10250 -2150);
FORCEPROP 3 LASTPIN (-10300 -2150) SIG_NAME GND\g
J 0
(-10290 -2140);
DISPLAY 0.659574 (-10290 -2140);
PAINT MONO (-10290 -2140);
DISPLAY INVISIBLE (-10290 -2140);
FORCEPROP 1 LAST PATH I57
R 1
J 0
(-10250 -2075);
DISPLAY 0.872340 (-10250 -2075);
PAINT AQUA (-10250 -2075);
DISPLAY INVISIBLE (-10250 -2075);
FORCEPROP 2 LAST CDS_LIB mstr_symbols
R 1
J 0
(-10250 -2150);
PAINT MONO (-10250 -2150);
DISPLAY INVISIBLE (-10250 -2150);
FORCEPROP 1 LAST SIZE 1B
R 1
J 0
(-10200 -2075);
DISPLAY 0.872340 (-10200 -2075);
PAINT AQUA (-10200 -2075);
DISPLAY INVISIBLE (-10200 -2075);
FORCEPROP 1 LAST VOLTAGE 0.0V
R 1
J 0
(-10207 -2195);
DISPLAY 0.340426 (-10207 -2195);
PAINT GREEN (-10207 -2195);
DISPLAY INVISIBLE (-10207 -2195);
FORCEPROP 1 LAST BODY_TYPE PLUMBING
R 1
J 0
(-10207 -2195);
DISPLAY 0.340426 (-10207 -2195);
PAINT GREEN (-10207 -2195);
DISPLAY INVISIBLE (-10207 -2195);
FORCEPROP 1 LAST HDL_POWER GND
R 1
J 0
(-10400 -2150);
DISPLAY 0.872340 (-10400 -2150);
PAINT GREEN (-10400 -2150);
DISPLAY INVISIBLE (-10400 -2150);
FORCEADD RES..2
R 7
(-10925 -2150);
FORCEPROP 1 LAST LOCATION R1T27
J 0
(-11146 -2134);
DISPLAY 0.617021 (-11146 -2134);
PAINT AQUA (-11146 -2134);
FORCEPROP 1 LAST PACK_TYPE 0402
J 0
(-10746 -2139);
DISPLAY 0.617021 (-10746 -2139);
PAINT SKYBLUE (-10746 -2139);
FORCEPROP 1 LAST VALUE 240
J 0
(-10846 -2134);
DISPLAY 0.617021 (-10846 -2134);
PAINT SKYBLUE (-10846 -2134);
FORCEPROP 1 LAST TOLERANCE 1.0%
J 0
(-10646 -2134);
DISPLAY 0.617021 (-10646 -2134);
PAINT SKYBLUE (-10646 -2134);
FORCEPROP 1 LASTPIN (-10825 -2150) $PN 1
R 1
J 0
(-10826 -2182);
DISPLAY 0.787234 (-10826 -2182);
PAINT ORANGE (-10826 -2182);
DISPLAY INVISIBLE (-10826 -2182);
FORCEPROP 1 LASTPIN (-11025 -2150) $PN 2
R 1
J 0
(-10978 -2182);
DISPLAY 0.787234 (-10978 -2182);
PAINT ORANGE (-10978 -2182);
DISPLAY INVISIBLE (-10978 -2182);
FORCEPROP 1 LAST PATH I58
R 1
J 0
(-10704 -2146);
DISPLAY 0.978723 (-10704 -2146);
PAINT WHITE (-10704 -2146);
DISPLAY INVISIBLE (-10704 -2146);
FORCEPROP 2 LAST CDS_LIB mstr_discrete
R 1
J 0
(-10878 -2197);
PAINT MONO (-10878 -2197);
DISPLAY INVISIBLE (-10878 -2197);
FORCEPROP 2 LAST BOM_COST SM_MEM
R 1
J 0
(-10652 -2148);
DISPLAY 1.021277 (-10652 -2148);
PAINT ORANGE (-10652 -2148);
DISPLAY INVISIBLE (-10652 -2148);
FORCEPROP 2 LAST ROOM BMC_MEMORY
R 1
J 0
(-10702 -2148);
DISPLAY 1.021277 (-10702 -2148);
PAINT ORANGE (-10702 -2148);
DISPLAY INVISIBLE (-10702 -2148);
FORCEPROP 1 LAST PART_NUMBER G21796-294
R 1
J 0
(-11021 -2139);
DISPLAY 0.617021 (-11021 -2139);
PAINT BLUE (-11021 -2139);
DISPLAY INVISIBLE (-11021 -2139);
FORCEPROP 1 LAST MATERIAL CHIP
R 1
J 0
(-10971 -2139);
DISPLAY 0.617021 (-10971 -2139);
PAINT SKYBLUE (-10971 -2139);
DISPLAY INVISIBLE (-10971 -2139);
FORCEPROP 1 LAST WATTAGE 1/16W
R 1
J 0
(-10921 -2139);
DISPLAY 0.617021 (-10921 -2139);
PAINT SKYBLUE (-10921 -2139);
DISPLAY INVISIBLE (-10921 -2139);
FORCEADD OFFPAGE..4
(-9425 -3775);
FORCEPROP 2 LAST $XR0 120 
J 0
(-9239 -3775);
DISPLAY 0.638298 (-9239 -3775);
PAINT MONO (-9239 -3775);
FORCEPROP 2 LAST $XR1 133 
J 0
(-9119 -3775);
DISPLAY 0.638298 (-9119 -3775);
PAINT MONO (-9119 -3775);
FORCEPROP 2 LAST $XR2 119 
J 0
(-8999 -3775);
DISPLAY 0.638298 (-8999 -3775);
PAINT MONO (-8999 -3775);
FORCEPROP 2 LAST PATH I59
J 0
(-8975 -3725);
DISPLAY 1.021277 (-8975 -3725);
PAINT ORANGE (-8975 -3725);
DISPLAY INVISIBLE (-8975 -3725);
FORCEPROP 2 LAST CDS_LIB mstr_standard
J 0
(-9425 -3775);
PAINT ORANGE (-9425 -3775);
DISPLAY INVISIBLE (-9425 -3775);
FORCEPROP 1 LAST OFFPAGE TRUE
J 0
(-9100 -3900);
DISPLAY 0.872340 (-9100 -3900);
PAINT GREEN (-9100 -3900);
DISPLAY INVISIBLE (-9100 -3900);
FORCEPROP 1 LAST COMMENT_BODY TRUE
J 0
(-9450 -3875);
DISPLAY 0.872340 (-9450 -3875);
PAINT GREEN (-9450 -3875);
DISPLAY INVISIBLE (-9450 -3875);
FORCEPROP 2 LAST $XR3 146 
J 0
(-8999 -3775);
DISPLAY 0.638298 (-8999 -3775);
PAINT MONO (-8999 -3775);
FORCEADD OFFPAGE..5
(-14375 -1450);
FORCEPROP 2 LAST $XR0 149 
J 0
(-14660 -1450);
DISPLAY 0.638298 (-14660 -1450);
PAINT MONO (-14660 -1450);
FORCEPROP 2 LAST PATH I6
J 0
(-14650 -1400);
DISPLAY 1.021277 (-14650 -1400);
PAINT ORANGE (-14650 -1400);
DISPLAY INVISIBLE (-14650 -1400);
FORCEPROP 2 LAST CDS_LIB mstr_standard
J 0
(-14375 -1450);
PAINT MONO (-14375 -1450);
DISPLAY INVISIBLE (-14375 -1450);
FORCEPROP 1 LAST OFFPAGE TRUE
J 0
(-14050 -1575);
DISPLAY 0.872340 (-14050 -1575);
PAINT GREEN (-14050 -1575);
DISPLAY INVISIBLE (-14050 -1575);
FORCEPROP 1 LAST COMMENT_BODY TRUE
J 0
(-14275 -1525);
DISPLAY 0.872340 (-14275 -1525);
PAINT GREEN (-14275 -1525);
DISPLAY INVISIBLE (-14275 -1525);
FORCEADD OFFPAGE..5
(-10350 -3975);
FORCEPROP 2 LAST $XR0 137 
J 0
(-10605 -3975);
DISPLAY 0.638298 (-10605 -3975);
PAINT MONO (-10605 -3975);
FORCEPROP 2 LAST PATH I60
J 0
(-10600 -3925);
DISPLAY 1.021277 (-10600 -3925);
PAINT ORANGE (-10600 -3925);
DISPLAY INVISIBLE (-10600 -3925);
FORCEPROP 2 LAST $XRERR ?
J 0
(-10749 -3975);
DISPLAY 0.638298 (-10749 -3975);
PAINT MONO (-10749 -3975);
DISPLAY INVISIBLE (-10749 -3975);
FORCEPROP 2 LAST $XRERR ?
J 0
(-10749 -3975);
DISPLAY 0.638298 (-10749 -3975);
PAINT MONO (-10749 -3975);
DISPLAY INVISIBLE (-10749 -3975);
FORCEPROP 2 LAST $XRERR ?
J 0
(-10749 -3975);
DISPLAY 0.638298 (-10749 -3975);
PAINT MONO (-10749 -3975);
DISPLAY INVISIBLE (-10749 -3975);
FORCEPROP 2 LAST $XRERR ?
J 0
(-10749 -3975);
DISPLAY 0.638298 (-10749 -3975);
PAINT MONO (-10749 -3975);
DISPLAY INVISIBLE (-10749 -3975);
FORCEPROP 2 LAST $XRERR ?
J 0
(-10749 -3975);
DISPLAY 0.638298 (-10749 -3975);
PAINT MONO (-10749 -3975);
DISPLAY INVISIBLE (-10749 -3975);
FORCEPROP 2 LAST $XRERR ?
J 0
(-10749 -3975);
DISPLAY 0.638298 (-10749 -3975);
PAINT MONO (-10749 -3975);
DISPLAY INVISIBLE (-10749 -3975);
FORCEPROP 2 LAST CDS_LIB mstr_standard
J 0
(-10350 -3975);
PAINT ORANGE (-10350 -3975);
DISPLAY INVISIBLE (-10350 -3975);
FORCEPROP 2 LAST $XRERR ?
J 0
(-10749 -3975);
DISPLAY 0.638298 (-10749 -3975);
PAINT MONO (-10749 -3975);
DISPLAY INVISIBLE (-10749 -3975);
FORCEPROP 2 LAST $XRERR ?
J 0
(-10749 -3975);
DISPLAY 0.638298 (-10749 -3975);
PAINT MONO (-10749 -3975);
DISPLAY INVISIBLE (-10749 -3975);
FORCEPROP 2 LAST $XRERR ?
J 0
(-10749 -3975);
DISPLAY 0.638298 (-10749 -3975);
PAINT MONO (-10749 -3975);
DISPLAY INVISIBLE (-10749 -3975);
FORCEPROP 2 LAST $XRERR ?
J 0
(-10749 -3975);
DISPLAY 0.638298 (-10749 -3975);
PAINT MONO (-10749 -3975);
DISPLAY INVISIBLE (-10749 -3975);
FORCEPROP 2 LAST $XRERR ?
J 0
(-10749 -3975);
DISPLAY 0.638298 (-10749 -3975);
PAINT MONO (-10749 -3975);
DISPLAY INVISIBLE (-10749 -3975);
FORCEPROP 2 LAST $XRERR ?
J 0
(-10749 -3975);
DISPLAY 0.638298 (-10749 -3975);
PAINT MONO (-10749 -3975);
DISPLAY INVISIBLE (-10749 -3975);
FORCEPROP 1 LAST OFFPAGE TRUE
J 0
(-10025 -4100);
DISPLAY 0.872340 (-10025 -4100);
PAINT GREEN (-10025 -4100);
DISPLAY INVISIBLE (-10025 -4100);
FORCEPROP 1 LAST COMMENT_BODY TRUE
J 0
(-10250 -4050);
DISPLAY 0.872340 (-10250 -4050);
PAINT GREEN (-10250 -4050);
DISPLAY INVISIBLE (-10250 -4050);
FORCEADD OFFPAGE..5
(-10350 -3925);
FORCEPROP 2 LAST $XR1 ?
J 0
(-10725 -3925);
DISPLAY 0.638298 (-10725 -3925);
PAINT MONO (-10725 -3925);
FORCEPROP 2 LAST $XR0 137 
J 0
(-10330 -3975);
DISPLAY 0.638298 (-10330 -3975);
PAINT MONO (-10330 -3975);
FORCEPROP 2 LAST PATH I61
J 0
(-10725 -3875);
DISPLAY 1.021277 (-10725 -3875);
PAINT ORANGE (-10725 -3875);
DISPLAY INVISIBLE (-10725 -3875);
FORCEPROP 2 LAST $XRERR ?
J 0
(-10749 -3925);
DISPLAY 0.638298 (-10749 -3925);
PAINT MONO (-10749 -3925);
DISPLAY INVISIBLE (-10749 -3925);
FORCEPROP 2 LAST $XRERR ?
J 0
(-10749 -3925);
DISPLAY 0.638298 (-10749 -3925);
PAINT MONO (-10749 -3925);
DISPLAY INVISIBLE (-10749 -3925);
FORCEPROP 2 LAST $XRERR ?
J 0
(-10749 -3925);
DISPLAY 0.638298 (-10749 -3925);
PAINT MONO (-10749 -3925);
DISPLAY INVISIBLE (-10749 -3925);
FORCEPROP 2 LAST $XRERR ?
J 0
(-10749 -3925);
DISPLAY 0.638298 (-10749 -3925);
PAINT MONO (-10749 -3925);
DISPLAY INVISIBLE (-10749 -3925);
FORCEPROP 2 LAST $XRERR ?
J 0
(-10749 -3925);
DISPLAY 0.638298 (-10749 -3925);
PAINT MONO (-10749 -3925);
DISPLAY INVISIBLE (-10749 -3925);
FORCEPROP 2 LAST $XRERR ?
J 0
(-10749 -3925);
DISPLAY 0.638298 (-10749 -3925);
PAINT MONO (-10749 -3925);
DISPLAY INVISIBLE (-10749 -3925);
FORCEPROP 2 LAST CDS_LIB mstr_standard
J 0
(-10350 -3925);
PAINT ORANGE (-10350 -3925);
DISPLAY INVISIBLE (-10350 -3925);
FORCEPROP 2 LAST $XRERR ?
J 0
(-10749 -3925);
DISPLAY 0.638298 (-10749 -3925);
PAINT MONO (-10749 -3925);
DISPLAY INVISIBLE (-10749 -3925);
FORCEPROP 2 LAST $XRERR ?
J 0
(-10749 -3925);
DISPLAY 0.638298 (-10749 -3925);
PAINT MONO (-10749 -3925);
DISPLAY INVISIBLE (-10749 -3925);
FORCEPROP 2 LAST $XRERR ?
J 0
(-10749 -3925);
DISPLAY 0.638298 (-10749 -3925);
PAINT MONO (-10749 -3925);
DISPLAY INVISIBLE (-10749 -3925);
FORCEPROP 2 LAST $XRERR ?
J 0
(-10749 -3925);
DISPLAY 0.638298 (-10749 -3925);
PAINT MONO (-10749 -3925);
DISPLAY INVISIBLE (-10749 -3925);
FORCEPROP 2 LAST $XRERR ?
J 0
(-10749 -3925);
DISPLAY 0.638298 (-10749 -3925);
PAINT MONO (-10749 -3925);
DISPLAY INVISIBLE (-10749 -3925);
FORCEPROP 2 LAST $XRERR ?
J 0
(-10749 -3925);
DISPLAY 0.638298 (-10749 -3925);
PAINT MONO (-10749 -3925);
DISPLAY INVISIBLE (-10749 -3925);
FORCEPROP 1 LAST OFFPAGE TRUE
J 0
(-10025 -4050);
DISPLAY 0.872340 (-10025 -4050);
PAINT GREEN (-10025 -4050);
DISPLAY INVISIBLE (-10025 -4050);
FORCEPROP 1 LAST COMMENT_BODY TRUE
J 0
(-10250 -4000);
DISPLAY 0.872340 (-10250 -4000);
PAINT GREEN (-10250 -4000);
DISPLAY INVISIBLE (-10250 -4000);
FORCEADD OFFPAGE..2
(-9825 -4100);
FORCEPROP 2 LAST $XR1 119 
J 0
(-9516 -4100);
DISPLAY 0.638298 (-9516 -4100);
PAINT MONO (-9516 -4100);
FORCEPROP 2 LAST $XR0 157 
J 0
(-9636 -4100);
DISPLAY 0.638298 (-9636 -4100);
PAINT MONO (-9636 -4100);
FORCEPROP 2 LAST PATH I62
J 0
(-9500 -4050);
DISPLAY 1.021277 (-9500 -4050);
PAINT ORANGE (-9500 -4050);
DISPLAY INVISIBLE (-9500 -4050);
FORCEPROP 2 LAST CDS_LIB mstr_standard
J 0
(-9825 -4100);
PAINT ORANGE (-9825 -4100);
DISPLAY INVISIBLE (-9825 -4100);
FORCEPROP 1 LAST OFFPAGE TRUE
J 0
(-9500 -4225);
DISPLAY 0.872340 (-9500 -4225);
PAINT GREEN (-9500 -4225);
DISPLAY INVISIBLE (-9500 -4225);
FORCEPROP 1 LAST COMMENT_BODY TRUE
J 0
(-9870 -4195);
DISPLAY 0.872340 (-9870 -4195);
PAINT GREEN (-9870 -4195);
DISPLAY INVISIBLE (-9870 -4195);
FORCEADD AST2520A1-GP-GP..1
(-12850 -1850);
FORCEPROP 1 LAST VALUE AST2520A1-GP-GP
J 0
(-13425 -2950);
DISPLAY 0.617021 (-13425 -2950);
PAINT GREEN (-13425 -2950);
FORCEPROP 1 LAST LOCATION U25W4
J 0
(-13425 -775);
DISPLAY 0.617021 (-13425 -775);
PAINT GREEN (-13425 -775);
FORCEPROP 2 LAST CDS_LIB w_hdl
J 0
(-12850 -1850);
PAINT MONO (-12850 -1850);
DISPLAY INVISIBLE (-12850 -1850);
FORCEPROP 1 LAST CDS_LMAN_SYM_OUTLINE -575,1050,575,-1050
J 0
(-12850 -1850);
DISPLAY 0.468085 (-12850 -1850);
PAINT GREEN (-12850 -1850);
DISPLAY INVISIBLE (-12850 -1850);
FORCEPROP 1 LAST PATH I63
J 0
(-12850 -1850);
DISPLAY 0.617021 (-12850 -1850);
PAINT GREEN (-12850 -1850);
DISPLAY INVISIBLE (-12850 -1850);
FORCEPROP 1 LAST PACK_TYPE ASIC2-GB1
J 0
(-12850 -1850);
DISPLAY 0.617021 (-12850 -1850);
PAINT GREEN (-12850 -1850);
DISPLAY INVISIBLE (-12850 -1850);
FORCEPROP 1 LAST PART_NUMBER 071.2520A.M001
J 0
(-12850 -1850);
DISPLAY 0.617021 (-12850 -1850);
PAINT GREEN (-12850 -1850);
DISPLAY INVISIBLE (-12850 -1850);
FORCEADD OFFPAGE..5
(-14375 -1400);
FORCEPROP 2 LAST $XR0 149 
J 0
(-14660 -1400);
DISPLAY 0.638298 (-14660 -1400);
PAINT MONO (-14660 -1400);
FORCEPROP 2 LAST PATH I7
J 0
(-14650 -1350);
DISPLAY 1.021277 (-14650 -1350);
PAINT ORANGE (-14650 -1350);
DISPLAY INVISIBLE (-14650 -1350);
FORCEPROP 2 LAST CDS_LIB mstr_standard
J 0
(-14375 -1400);
PAINT MONO (-14375 -1400);
DISPLAY INVISIBLE (-14375 -1400);
FORCEPROP 1 LAST OFFPAGE TRUE
J 0
(-14050 -1525);
DISPLAY 0.872340 (-14050 -1525);
PAINT GREEN (-14050 -1525);
DISPLAY INVISIBLE (-14050 -1525);
FORCEPROP 1 LAST COMMENT_BODY TRUE
J 0
(-14275 -1475);
DISPLAY 0.872340 (-14275 -1475);
PAINT GREEN (-14275 -1475);
DISPLAY INVISIBLE (-14275 -1475);
FORCEADD OFFPAGE..5
(-14375 -1700);
FORCEPROP 2 LAST $XR0 149 
J 0
(-14660 -1700);
DISPLAY 0.638298 (-14660 -1700);
PAINT MONO (-14660 -1700);
FORCEPROP 2 LAST CDS_LIB mstr_standard
J 0
(-14375 -1700);
PAINT MONO (-14375 -1700);
DISPLAY INVISIBLE (-14375 -1700);
FORCEPROP 2 LAST PATH I8
J 0
(-14650 -1650);
DISPLAY 1.021277 (-14650 -1650);
PAINT ORANGE (-14650 -1650);
DISPLAY INVISIBLE (-14650 -1650);
FORCEPROP 1 LAST OFFPAGE TRUE
J 0
(-14050 -1825);
DISPLAY 0.872340 (-14050 -1825);
PAINT GREEN (-14050 -1825);
DISPLAY INVISIBLE (-14050 -1825);
FORCEPROP 1 LAST COMMENT_BODY TRUE
J 0
(-14275 -1775);
DISPLAY 0.872340 (-14275 -1775);
PAINT GREEN (-14275 -1775);
DISPLAY INVISIBLE (-14275 -1775);
FORCEADD OFFPAGE..5
(-14375 -1350);
FORCEPROP 2 LAST $XR0 149 
J 0
(-14660 -1350);
DISPLAY 0.638298 (-14660 -1350);
PAINT MONO (-14660 -1350);
FORCEPROP 2 LAST CDS_LIB mstr_standard
J 0
(-14375 -1350);
PAINT MONO (-14375 -1350);
DISPLAY INVISIBLE (-14375 -1350);
FORCEPROP 2 LAST PATH I9
J 0
(-14650 -1300);
DISPLAY 1.021277 (-14650 -1300);
PAINT ORANGE (-14650 -1300);
DISPLAY INVISIBLE (-14650 -1300);
FORCEPROP 1 LAST OFFPAGE TRUE
J 0
(-14050 -1475);
DISPLAY 0.872340 (-14050 -1475);
PAINT GREEN (-14050 -1475);
DISPLAY INVISIBLE (-14050 -1475);
FORCEPROP 1 LAST COMMENT_BODY TRUE
J 0
(-14275 -1425);
DISPLAY 0.872340 (-14275 -1425);
PAINT GREEN (-14275 -1425);
DISPLAY INVISIBLE (-14275 -1425);
FORCEADD INTEL_CORP_BPAGE..1
(-8225 -4750);
FORCEPROP 1 LAST CDS_CON_LAST_MODIFIED Tue Dec 01 11:52:04 2015
J 0
(-9650 -4425);
DISPLAY 1.361702 (-9650 -4425);
PAINT GREEN (-9650 -4425);
DISPLAY INVISIBLE (-9650 -4425);
FORCEPROP 2 LAST CUSTOM_TXT_CDS <XR_PAGE_TITLE>
J 0
(-16115 500);
DISPLAY 0.638298 (-16115 500);
PAINT PINK (-16115 500);
DISPLAY INVISIBLE (-16115 500);
FORCEPROP 2 LAST CUSTOM_TXT_CDS <CURRENT_DESIGN_SHEET> OF <TOTAL_DESIGN_SHEETS>
J 0
(-8725 -4725);
PAINT ORANGE (-8725 -4725);
FORCEPROP 2 LAST CUSTOM_TXT_CDS <CON_LAST_MODIFIED>
J 0
(-14625 -4625);
DISPLAY 1.361702 (-14625 -4625);
PAINT GREEN (-14625 -4625);
FORCEPROP 1 LAST SCH_ADDRESS1 2200 Mission College Blvd.
J 0
(-12200 -4625);
DISPLAY 0.617021 (-12200 -4625);
PAINT GREEN (-12200 -4625);
FORCEPROP 1 LAST SCH_ADDRESS2 P.O. BOX 58119
J 0
(-12200 -4675);
DISPLAY 0.617021 (-12200 -4675);
PAINT GREEN (-12200 -4675);
FORCEPROP 1 LAST SCH_ADDRESS3 Santa Clara, CA 95052-8119
J 0
(-12200 -4725);
DISPLAY 0.617021 (-12200 -4725);
PAINT GREEN (-12200 -4725);
FORCEPROP 1 LAST SCH_TITLE BMC (1 OF 7)
J 0
(-16175 -4700);
DISPLAY 1.212766 (-16175 -4700);
PAINT ORANGE (-16175 -4700);
FORCEPROP 1 LAST SCH_DEPT BESD
J 1
(-12675 -4650);
DISPLAY 1.212766 (-12675 -4650);
PAINT YELLOW (-12675 -4650);
FORCEPROP 1 LAST SCH_NUMBER H4694802
J 0
(-9525 -4600);
DISPLAY 1.212766 (-9525 -4600);
PAINT YELLOW (-9525 -4600);
FORCEPROP 1 LAST SCH_REV 2.420
J 0
(-8475 -4600);
DISPLAY 0.978723 (-8475 -4600);
PAINT YELLOW (-8475 -4600);
FORCEPROP 2 LAST CDS_LIB mstr_symbols
J 0
(-8225 -4750);
DISPLAY 1.361702 (-8225 -4750);
PAINT ORANGE (-8225 -4750);
DISPLAY INVISIBLE (-8225 -4750);
FORCEPROP 2 LAST PAGE_BORDER TRUE
J 0
(-16115 500);
DISPLAY 0.851064 (-16115 500);
PAINT PINK (-16115 500);
DISPLAY INVISIBLE (-16115 500);
FORCEPROP 1 LAST COMMENT_BODY TRUE
J 0
(-8213 -4738);
DISPLAY 0.617021 (-8213 -4738);
PAINT GREEN (-8213 -4738);
DISPLAY INVISIBLE (-8213 -4738);
FORCEPROP 2 LAST CDS_XR_PAGE_TITLE CR-143 : @BASEBOARD_FAB2_LIB.BASEBOARD_FAB2(SCH_1):PAGE143
J 0
(-16115 500);
DISPLAY 0.638298 (-16115 500);
PAINT PINK (-16115 500);
DISPLAY INVISIBLE (-16115 500);
WIRE 16 -1 (-10825 -2150)(-10300 -2150);
WIRE 16 -1 (-10400 -2200)(-10300 -2200);
WIRE 16 -1 (-10400 -3775)(-9475 -3775);
FORCEPROP 2 LAST SIG_NAME IRQ_PCH_NIC_ALERT_N
J 0
(-9960 -3765);
DISPLAY 0.617021 (-9960 -3765);
PAINT ORANGE (-9960 -3765);
WIRE 16 -1 (-10300 -3925)(-9250 -3925);
FORCEPROP 2 LAST SIG_NAME FM_ROMA<0>
J 0
(-10235 -3915);
DISPLAY 0.617021 (-10235 -3915);
PAINT ORANGE (-10235 -3915);
WIRE 16 -1 (-10300 -3975)(-9250 -3975);
FORCEPROP 2 LAST SIG_NAME FM_BMC_DISABLE
J 0
(-10235 -3965);
DISPLAY 0.617021 (-10235 -3965);
PAINT ORANGE (-10235 -3965);
WIRE 3 2175 (-11250 -3450)(-11250 -4225);
WIRE 3 2175 (-11250 -3450)(-8650 -3450);
WIRE 3 2175 (-11250 -4225)(-8650 -4225);
WIRE 3 2175 (-8650 -3450)(-8650 -4225);
WIRE 16 -1 (-11100 -2750)(-12125 -2750);
FORCEPROP 2 LAST SIG_NAME BMC_M_ODT
J 0
(-11935 -2740);
DISPLAY 0.680851 (-11935 -2740);
PAINT ORANGE (-11935 -2740);
WIRE 16 -1 (-12125 -2050)(-11100 -2050);
FORCEPROP 2 LAST SIG_NAME BMC_M_DM0
J 0
(-11960 -2040);
DISPLAY 0.680851 (-11960 -2040);
PAINT ORANGE (-11960 -2040);
WIRE 16 -1 (-11025 -2150)(-12125 -2150);
FORCEPROP 2 LAST SIG_NAME BMC_MIOZ
J 0
(-11835 -2140);
DISPLAY 0.680851 (-11835 -2140);
PAINT ORANGE (-11835 -2140);
FORCEPROP 2 LASTPROP $XRERR UNIQUE?
J 0
(-12075 -2140);
DISPLAY 0.638298 (-12075 -2140);
PAINT MONO (-12075 -2140);
DISPLAY INVISIBLE (-12075 -2140);
WIRE 16 -1 (-10600 -2200)(-12125 -2200);
FORCEPROP 2 LAST SIG_NAME BMC_M_VREFCA
J 0
(-11860 -2190);
DISPLAY 0.680851 (-11860 -2190);
PAINT ORANGE (-11860 -2190);
FORCEPROP 2 LASTPROP $XR0 149 
J 0
(-11986 -2190);
DISPLAY 0.638298 (-11986 -2190);
PAINT MONO (-11986 -2190);
WIRE 16 -1 (-12125 -2300)(-11100 -2300);
FORCEPROP 2 LAST SIG_NAME BMC_M_CS_N
J 0
(-11960 -2290);
DISPLAY 0.680851 (-11960 -2290);
PAINT ORANGE (-11960 -2290);
WIRE 16 -1 (-12125 -2550)(-11100 -2550);
FORCEPROP 2 LAST SIG_NAME BMC_M_CLK_DP
J 0
(-11935 -2540);
DISPLAY 0.680851 (-11935 -2540);
PAINT ORANGE (-11935 -2540);
WIRE 16 -1 (-12125 -2700)(-11100 -2700);
FORCEPROP 2 LAST SIG_NAME BMC_M_CKE
J 0
(-11935 -2690);
DISPLAY 0.680851 (-11935 -2690);
PAINT ORANGE (-11935 -2690);
WIRE 16 -1 (-10375 -4100)(-9875 -4100);
FORCEPROP 2 LAST SIG_NAME FM_BMC_ENABLE_N
J 0
(-10285 -4090);
DISPLAY 0.617021 (-10285 -4090);
PAINT ORANGE (-10285 -4090);
WIRE 16 -1 (-12125 -1150)(-11100 -1150);
FORCEPROP 2 LAST SIG_NAME BMC_M_A11
J 0
(-11910 -1140);
DISPLAY 0.680851 (-11910 -1140);
PAINT ORANGE (-11910 -1140);
WIRE 16 -1 (-12125 -1300)(-11100 -1300);
FORCEPROP 2 LAST SIG_NAME BMC_M_A8
J 0
(-11910 -1290);
DISPLAY 0.680851 (-11910 -1290);
PAINT ORANGE (-11910 -1290);
WIRE 16 -1 (-12125 -1800)(-11100 -1800);
FORCEPROP 2 LAST SIG_NAME BMC_M_BG0
J 0
(-11935 -1790);
DISPLAY 0.680851 (-11935 -1790);
PAINT ORANGE (-11935 -1790);
WIRE 16 -1 (-12125 -1450)(-11100 -1450);
FORCEPROP 2 LAST SIG_NAME BMC_M_A5
J 0
(-11910 -1440);
DISPLAY 0.680851 (-11910 -1440);
PAINT ORANGE (-11910 -1440);
WIRE 16 -1 (-12125 -1500)(-11100 -1500);
FORCEPROP 2 LAST SIG_NAME BMC_M_A4
J 0
(-11910 -1490);
DISPLAY 0.680851 (-11910 -1490);
PAINT ORANGE (-11910 -1490);
WIRE 16 -1 (-12125 -2450)(-11100 -2450);
FORCEPROP 2 LAST SIG_NAME BMC_M_WE_N
J 0
(-11935 -2440);
DISPLAY 0.680851 (-11935 -2440);
PAINT ORANGE (-11935 -2440);
WIRE 16 -1 (-12125 -2400)(-11100 -2400);
FORCEPROP 2 LAST SIG_NAME BMC_M_CAS_N
J 0
(-11985 -2390);
DISPLAY 0.680851 (-11985 -2390);
PAINT ORANGE (-11985 -2390);
WIRE 16 -1 (-12125 -1100)(-11100 -1100);
FORCEPROP 2 LAST SIG_NAME BMC_M_A12
J 0
(-11910 -1090);
DISPLAY 0.680851 (-11910 -1090);
PAINT ORANGE (-11910 -1090);
WIRE 16 -1 (-12125 -950)(-11100 -950);
FORCEPROP 2 LAST SIG_NAME TP_BMC_M_A15
J 0
(-11910 -940);
DISPLAY 0.680851 (-11910 -940);
PAINT ORANGE (-11910 -940);
FORCEPROP 2 LASTPROP $XRERR UNIQUE?
J 0
(-11070 -950);
DISPLAY 0.638298 (-11070 -950);
PAINT MONO (-11070 -950);
DISPLAY INVISIBLE (-11070 -950);
WIRE 16 -1 (-12125 -1000)(-11100 -1000);
FORCEPROP 2 LAST SIG_NAME BMC_M_MACT_N
J 0
(-11910 -990);
DISPLAY 0.680851 (-11910 -990);
PAINT ORANGE (-11910 -990);
WIRE 16 -1 (-12125 -1200)(-11100 -1200);
FORCEPROP 2 LAST SIG_NAME BMC_M_A10
J 0
(-11910 -1190);
DISPLAY 0.680851 (-11910 -1190);
PAINT ORANGE (-11910 -1190);
WIRE 16 -1 (-12125 -1050)(-11100 -1050);
FORCEPROP 2 LAST SIG_NAME BMC_M_A13
J 0
(-11910 -1040);
DISPLAY 0.680851 (-11910 -1040);
PAINT ORANGE (-11910 -1040);
WIRE 16 -1 (-13575 -2000)(-14325 -2000);
FORCEPROP 2 LAST SIG_NAME BMC_M_DQS1_DN
J 0
(-14210 -1990);
DISPLAY 0.680851 (-14210 -1990);
PAINT ORANGE (-14210 -1990);
WIRE 16 -1 (-12125 -2000)(-11100 -2000);
FORCEPROP 2 LAST SIG_NAME BMC_M_DM1
J 0
(-11960 -1990);
DISPLAY 0.680851 (-11960 -1990);
PAINT ORANGE (-11960 -1990);
WIRE 16 -1 (-12125 -2600)(-11100 -2600);
FORCEPROP 2 LAST SIG_NAME BMC_M_CLK_DN
J 0
(-11910 -2590);
DISPLAY 0.680851 (-11910 -2590);
PAINT ORANGE (-11910 -2590);
WIRE 16 -1 (-12125 -2350)(-11100 -2350);
FORCEPROP 2 LAST SIG_NAME BMC_M_RAS_N
J 0
(-11985 -2340);
DISPLAY 0.680851 (-11985 -2340);
PAINT ORANGE (-11985 -2340);
WIRE 16 -1 (-12125 -1900)(-11100 -1900);
FORCEPROP 2 LAST SIG_NAME BMC_M_BA0
J 0
(-11935 -1890);
DISPLAY 0.680851 (-11935 -1890);
PAINT ORANGE (-11935 -1890);
WIRE 16 -1 (-12125 -1700)(-11100 -1700);
FORCEPROP 2 LAST SIG_NAME BMC_M_A0
J 0
(-11910 -1690);
DISPLAY 0.680851 (-11910 -1690);
PAINT ORANGE (-11910 -1690);
WIRE 16 -1 (-12125 -1850)(-11100 -1850);
FORCEPROP 2 LAST SIG_NAME BMC_M_BA1
J 0
(-11935 -1840);
DISPLAY 0.680851 (-11935 -1840);
PAINT ORANGE (-11935 -1840);
WIRE 16 -1 (-12125 -1650)(-11100 -1650);
FORCEPROP 2 LAST SIG_NAME BMC_M_A1
J 0
(-11910 -1640);
DISPLAY 0.680851 (-11910 -1640);
PAINT ORANGE (-11910 -1640);
WIRE 16 -1 (-12125 -1550)(-11100 -1550);
FORCEPROP 2 LAST SIG_NAME BMC_M_A3
J 0
(-11910 -1540);
DISPLAY 0.680851 (-11910 -1540);
PAINT ORANGE (-11910 -1540);
WIRE 16 -1 (-12125 -1600)(-11100 -1600);
FORCEPROP 2 LAST SIG_NAME BMC_M_A2
J 0
(-11910 -1590);
DISPLAY 0.680851 (-11910 -1590);
PAINT ORANGE (-11910 -1590);
WIRE 16 -1 (-12125 -1400)(-11100 -1400);
FORCEPROP 2 LAST SIG_NAME BMC_M_A6
J 0
(-11910 -1390);
DISPLAY 0.680851 (-11910 -1390);
PAINT ORANGE (-11910 -1390);
WIRE 16 -1 (-12125 -1350)(-11100 -1350);
FORCEPROP 2 LAST SIG_NAME BMC_M_A7
J 0
(-11910 -1340);
DISPLAY 0.680851 (-11910 -1340);
PAINT ORANGE (-11910 -1340);
WIRE 16 -1 (-12125 -1250)(-11100 -1250);
FORCEPROP 2 LAST SIG_NAME BMC_M_A9
J 0
(-11910 -1240);
DISPLAY 0.680851 (-11910 -1240);
PAINT ORANGE (-11910 -1240);
WIRE 16 -1 (-13575 -1850)(-14325 -1850);
FORCEPROP 2 LAST SIG_NAME BMC_M_DQS0_DN
J 0
(-14210 -1840);
DISPLAY 0.680851 (-14210 -1840);
PAINT ORANGE (-14210 -1840);
WIRE 16 -1 (-13575 -1800)(-14325 -1800);
FORCEPROP 2 LAST SIG_NAME BMC_M_DQS0_DP
J 0
(-14210 -1790);
DISPLAY 0.680851 (-14210 -1790);
PAINT ORANGE (-14210 -1790);
WIRE 16 -1 (-14325 -1650)(-13575 -1650);
FORCEPROP 2 LAST SIG_NAME BMC_M_DQ1
J 0
(-14210 -1640);
DISPLAY 0.680851 (-14210 -1640);
PAINT ORANGE (-14210 -1640);
WIRE 16 -1 (-14325 -1550)(-13575 -1550);
FORCEPROP 2 LAST SIG_NAME BMC_M_DQ3
J 0
(-14210 -1540);
DISPLAY 0.680851 (-14210 -1540);
PAINT ORANGE (-14210 -1540);
WIRE 16 -1 (-14325 -1450)(-13575 -1450);
FORCEPROP 2 LAST SIG_NAME BMC_M_DQ5
J 0
(-14210 -1440);
DISPLAY 0.680851 (-14210 -1440);
PAINT ORANGE (-14210 -1440);
WIRE 16 -1 (-14325 -1350)(-13575 -1350);
FORCEPROP 2 LAST SIG_NAME BMC_M_DQ7
J 0
(-14210 -1340);
DISPLAY 0.680851 (-14210 -1340);
PAINT ORANGE (-14210 -1340);
WIRE 16 -1 (-14325 -1250)(-13575 -1250);
FORCEPROP 2 LAST SIG_NAME BMC_M_DQ9
J 0
(-14210 -1240);
DISPLAY 0.680851 (-14210 -1240);
PAINT ORANGE (-14210 -1240);
WIRE 16 -1 (-14325 -1150)(-13575 -1150);
FORCEPROP 2 LAST SIG_NAME BMC_M_DQ11
J 0
(-14210 -1140);
DISPLAY 0.680851 (-14210 -1140);
PAINT ORANGE (-14210 -1140);
WIRE 16 -1 (-14325 -1050)(-13575 -1050);
FORCEPROP 2 LAST SIG_NAME BMC_M_DQ13
J 0
(-14210 -1040);
DISPLAY 0.680851 (-14210 -1040);
PAINT ORANGE (-14210 -1040);
WIRE 16 -1 (-13575 -950)(-14325 -950);
FORCEPROP 2 LAST SIG_NAME BMC_M_DQ15
J 0
(-14210 -940);
DISPLAY 0.680851 (-14210 -940);
PAINT ORANGE (-14210 -940);
WIRE 16 -1 (-13575 -1950)(-14325 -1950);
FORCEPROP 2 LAST SIG_NAME BMC_M_DQS1_DP
J 0
(-14210 -1940);
DISPLAY 0.680851 (-14210 -1940);
PAINT ORANGE (-14210 -1940);
WIRE 16 -1 (-14325 -1700)(-13575 -1700);
FORCEPROP 2 LAST SIG_NAME BMC_M_DQ0
J 0
(-14210 -1690);
DISPLAY 0.680851 (-14210 -1690);
PAINT ORANGE (-14210 -1690);
WIRE 16 -1 (-14325 -1600)(-13575 -1600);
FORCEPROP 2 LAST SIG_NAME BMC_M_DQ2
J 0
(-14210 -1590);
DISPLAY 0.680851 (-14210 -1590);
PAINT ORANGE (-14210 -1590);
WIRE 16 -1 (-14325 -1500)(-13575 -1500);
FORCEPROP 2 LAST SIG_NAME BMC_M_DQ4
J 0
(-14210 -1490);
DISPLAY 0.680851 (-14210 -1490);
PAINT ORANGE (-14210 -1490);
WIRE 16 -1 (-14325 -1400)(-13575 -1400);
FORCEPROP 2 LAST SIG_NAME BMC_M_DQ6
J 0
(-14210 -1390);
DISPLAY 0.680851 (-14210 -1390);
PAINT ORANGE (-14210 -1390);
WIRE 16 -1 (-14325 -1300)(-13575 -1300);
FORCEPROP 2 LAST SIG_NAME BMC_M_DQ8
J 0
(-14210 -1290);
DISPLAY 0.680851 (-14210 -1290);
PAINT ORANGE (-14210 -1290);
WIRE 16 -1 (-14325 -1200)(-13575 -1200);
FORCEPROP 2 LAST SIG_NAME BMC_M_DQ10
J 0
(-14210 -1190);
DISPLAY 0.680851 (-14210 -1190);
PAINT ORANGE (-14210 -1190);
WIRE 16 -1 (-14325 -1100)(-13575 -1100);
FORCEPROP 2 LAST SIG_NAME BMC_M_DQ12
J 0
(-14210 -1090);
DISPLAY 0.680851 (-14210 -1090);
PAINT ORANGE (-14210 -1090);
WIRE 16 -1 (-14325 -1000)(-13575 -1000);
FORCEPROP 2 LAST SIG_NAME BMC_M_DQ14
J 0
(-14210 -990);
DISPLAY 0.680851 (-14210 -990);
PAINT ORANGE (-14210 -990);
FORCENOTE
ROOM=BMC
(-16125 -4450) 0;
DISPLAY LEFT (-16125 -4450);
DISPLAY 1.595745 (-16125 -4450);
PAINT PURPLE (-16125 -4450);
FORCENOTE
BOM_COST=SM_CONTROLLER
(-16125 -4550) 0;
DISPLAY LEFT (-16125 -4550);
DISPLAY 1.595745 (-16125 -4550);
PAINT PURPLE (-16125 -4550);
FORCENOTE
UNKNOW GPIO
(-10575 -3525) 0;
DISPLAY LEFT (-10575 -3525);
DISPLAY 1.021277 (-10575 -3525);
PAINT RED (-10575 -3525);
QUIT
